(kicad_pcb
	(version 20260206)
	(generator "pcbnew")
	(generator_version "10.0")
	(general
		(thickness 1.6)
		(legacy_teardrops no)
	)
	(paper "A4")
	(title_block
		(title "01162023_DA0F0TEBIF0_F0T_Expander_BD_F_brd_V02_OCP.brd")
		(comment 1 "Grand Teton / footprints 8904-8914 of 9728")
	)
	(layers
		(0 "F.Cu" signal "TOP")
		(4 "In1.Cu" signal "GND")
		(6 "In2.Cu" signal "VCC")
		(8 "In3.Cu" signal "VCC1")
		(10 "In4.Cu" signal "GND1")
		(12 "In5.Cu" signal "IN1")
		(14 "In6.Cu" signal "GND2")
		(16 "In7.Cu" signal "IN2")
		(18 "In8.Cu" signal "GND3")
		(20 "In9.Cu" signal "IN3")
		(22 "In10.Cu" signal "GND4")
		(24 "In11.Cu" signal "IN4")
		(26 "In12.Cu" signal "GND5")
		(28 "In13.Cu" signal "IN5")
		(30 "In14.Cu" signal "GND6")
		(32 "In15.Cu" signal "IN6")
		(34 "In16.Cu" signal "GND7")
		(2 "B.Cu" signal "BOTTOM")
		(9 "F.Adhes" user "F.Adhesive")
		(11 "B.Adhes" user "B.Adhesive")
		(13 "F.Paste" user "Package Geometry/Pastemask Top")
		(15 "B.Paste" user "Package Geometry/Pastemask Bottom")
		(5 "F.SilkS" user "Ref Des/Silkscreen Top")
		(7 "B.SilkS" user "Ref Des/Silkscreen Bottom")
		(1 "F.Mask" user "Board Geometry/Soldermask Top")
		(3 "B.Mask" user "Board Geometry/Soldermask Bottom")
		(17 "Dwgs.User" user "User.Drawings")
		(19 "Cmts.User" user "User.Comments")
		(21 "Eco1.User" user "User.Eco1")
		(23 "Eco2.User" user "User.Eco2")
		(25 "Edge.Cuts" user "Board Geometry/Outline")
		(27 "Margin" user)
		(31 "F.CrtYd" user "Package Geometry/Place Bound Top")
		(29 "B.CrtYd" user "Package Geometry/Place Bound Bottom")
		(35 "F.Fab" user "Ref Des/Assembly Top")
		(33 "B.Fab" user "Ref Des/Assembly Bottom")
	)
	(footprint ""
		(layer "B.Cu")
		(at 412.699962 -303.499774 -90)
		(property "Reference" "C3460"
			(at 0 0 90)
			(layer "B.SilkS")
			(hide yes)
			(effects
				(font
					(size 1.27 1.27)
				)
				(justify mirror)
			)
		)
		(property "Value" ""
			(at 0 0 90)
			(layer "B.Fab")
			(effects
				(font
					(size 1.27 1.27)
				)
				(justify mirror)
			)
		)
		(duplicate_pad_numbers_are_jumpers no)
		(fp_line
			(start -0.299974 0.150114)
			(end 0.299974 0.150114)
			(stroke
				(width 0.1)
				(type default)
			)
			(layer "B.Fab")
		)
		(fp_line
			(start 0.299974 0.150114)
			(end 0.299974 -0.150114)
			(stroke
				(width 0.1)
				(type default)
			)
			(layer "B.Fab")
		)
		(fp_line
			(start -0.299974 -0.150114)
			(end -0.299974 0.150114)
			(stroke
				(width 0.1)
				(type default)
			)
			(layer "B.Fab")
		)
		(fp_line
			(start 0.299974 -0.150114)
			(end -0.299974 -0.150114)
			(stroke
				(width 0.1)
				(type default)
			)
			(layer "B.Fab")
		)
		(pad "1" smd rect
			(at 0.2667 0 90)
			(size 0.3048 0.381)
			(layers "B.Cu" "B.Mask" "B.Paste")
			(net "P1V25_PEX3")
		)
		(pad "2" smd rect
			(at -0.2667 0 90)
			(size 0.3048 0.381)
			(layers "B.Cu" "B.Mask" "B.Paste")
			(net "GND")
		)
	)
	(footprint ""
		(layer "B.Cu")
		(at 172.900086 -299.699934 -90)
		(property "Reference" "C1455"
			(at 0 0 90)
			(layer "B.SilkS")
			(hide yes)
			(effects
				(font
					(size 1.27 1.27)
				)
				(justify mirror)
			)
		)
		(property "Value" ""
			(at 0 0 90)
			(layer "B.Fab")
			(effects
				(font
					(size 1.27 1.27)
				)
				(justify mirror)
			)
		)
		(duplicate_pad_numbers_are_jumpers no)
		(fp_line
			(start -0.299974 0.150114)
			(end 0.299974 0.150114)
			(stroke
				(width 0.1)
				(type default)
			)
			(layer "B.Fab")
		)
		(fp_line
			(start 0.299974 0.150114)
			(end 0.299974 -0.150114)
			(stroke
				(width 0.1)
				(type default)
			)
			(layer "B.Fab")
		)
		(fp_line
			(start -0.299974 -0.150114)
			(end -0.299974 0.150114)
			(stroke
				(width 0.1)
				(type default)
			)
			(layer "B.Fab")
		)
		(fp_line
			(start 0.299974 -0.150114)
			(end -0.299974 -0.150114)
			(stroke
				(width 0.1)
				(type default)
			)
			(layer "B.Fab")
		)
		(pad "1" smd rect
			(at 0.2667 0 90)
			(size 0.3048 0.381)
			(layers "B.Cu" "B.Mask" "B.Paste")
			(net "P0V8_SERDES_VDDA_PEX1")
		)
		(pad "2" smd rect
			(at -0.2667 0 90)
			(size 0.3048 0.381)
			(layers "B.Cu" "B.Mask" "B.Paste")
			(net "GND")
		)
	)
	(footprint ""
		(layer "B.Cu")
		(at 296.1513 -305.399948 -90)
		(property "Reference" "C3301"
			(at 0 0 90)
			(layer "B.SilkS")
			(hide yes)
			(effects
				(font
					(size 1.27 1.27)
				)
				(justify mirror)
			)
		)
		(property "Value" ""
			(at 0 0 90)
			(layer "B.Fab")
			(effects
				(font
					(size 1.27 1.27)
				)
				(justify mirror)
			)
		)
		(duplicate_pad_numbers_are_jumpers no)
		(fp_line
			(start -0.299974 0.150114)
			(end 0.299974 0.150114)
			(stroke
				(width 0.1)
				(type default)
			)
			(layer "B.Fab")
		)
		(fp_line
			(start 0.299974 0.150114)
			(end 0.299974 -0.150114)
			(stroke
				(width 0.1)
				(type default)
			)
			(layer "B.Fab")
		)
		(fp_line
			(start -0.299974 -0.150114)
			(end -0.299974 0.150114)
			(stroke
				(width 0.1)
				(type default)
			)
			(layer "B.Fab")
		)
		(fp_line
			(start 0.299974 -0.150114)
			(end -0.299974 -0.150114)
			(stroke
				(width 0.1)
				(type default)
			)
			(layer "B.Fab")
		)
		(pad "1" smd rect
			(at 0.2667 0 90)
			(size 0.3048 0.381)
			(layers "B.Cu" "B.Mask" "B.Paste")
			(net "P1V25_SERDES_VDDPLL_PEX2")
		)
		(pad "2" smd rect
			(at -0.2667 0 90)
			(size 0.3048 0.381)
			(layers "B.Cu" "B.Mask" "B.Paste")
			(net "GND")
		)
	)
	(footprint ""
		(layer "B.Cu")
		(at 49.1998 -300.174914)
		(property "Reference" "C1131"
			(at 0 0 0)
			(layer "B.SilkS")
			(hide yes)
			(effects
				(font
					(size 1.27 1.27)
				)
				(justify mirror)
			)
		)
		(property "Value" ""
			(at 0 0 0)
			(layer "B.Fab")
			(effects
				(font
					(size 1.27 1.27)
				)
				(justify mirror)
			)
		)
		(duplicate_pad_numbers_are_jumpers no)
		(fp_line
			(start -0.299974 -0.150114)
			(end -0.299974 0.150114)
			(stroke
				(width 0.1)
				(type default)
			)
			(layer "B.Fab")
		)
		(fp_line
			(start -0.299974 0.150114)
			(end 0.299974 0.150114)
			(stroke
				(width 0.1)
				(type default)
			)
			(layer "B.Fab")
		)
		(fp_line
			(start 0.299974 -0.150114)
			(end -0.299974 -0.150114)
			(stroke
				(width 0.1)
				(type default)
			)
			(layer "B.Fab")
		)
		(fp_line
			(start 0.299974 0.150114)
			(end 0.299974 -0.150114)
			(stroke
				(width 0.1)
				(type default)
			)
			(layer "B.Fab")
		)
		(pad "1" smd rect
			(at 0.2667 0 180)
			(size 0.3048 0.381)
			(layers "B.Cu" "B.Mask" "B.Paste")
			(net "P0V8_PEX0")
		)
		(pad "2" smd rect
			(at -0.2667 0 180)
			(size 0.3048 0.381)
			(layers "B.Cu" "B.Mask" "B.Paste")
			(net "GND")
		)
	)
	(footprint ""
		(layer "B.Cu")
		(at 180.02504 -293.99992 -90)
		(property "Reference" "C1408"
			(at 0 0 90)
			(layer "B.SilkS")
			(hide yes)
			(effects
				(font
					(size 1.27 1.27)
				)
				(justify mirror)
			)
		)
		(property "Value" ""
			(at 0 0 90)
			(layer "B.Fab")
			(effects
				(font
					(size 1.27 1.27)
				)
				(justify mirror)
			)
		)
		(duplicate_pad_numbers_are_jumpers no)
		(fp_line
			(start -0.299974 0.150114)
			(end 0.299974 0.150114)
			(stroke
				(width 0.1)
				(type default)
			)
			(layer "B.Fab")
		)
		(fp_line
			(start 0.299974 0.150114)
			(end 0.299974 -0.150114)
			(stroke
				(width 0.1)
				(type default)
			)
			(layer "B.Fab")
		)
		(fp_line
			(start -0.299974 -0.150114)
			(end -0.299974 0.150114)
			(stroke
				(width 0.1)
				(type default)
			)
			(layer "B.Fab")
		)
		(fp_line
			(start 0.299974 -0.150114)
			(end -0.299974 -0.150114)
			(stroke
				(width 0.1)
				(type default)
			)
			(layer "B.Fab")
		)
		(pad "1" smd rect
			(at 0.2667 0 90)
			(size 0.3048 0.381)
			(layers "B.Cu" "B.Mask" "B.Paste")
			(net "P0V8_PEX1")
		)
		(pad "2" smd rect
			(at -0.2667 0 90)
			(size 0.3048 0.381)
			(layers "B.Cu" "B.Mask" "B.Paste")
			(net "GND")
		)
	)
	(footprint ""
		(layer "B.Cu")
		(at 174.820326 -296.37482)
		(property "Reference" "C1362"
			(at 0 0 0)
			(layer "B.SilkS")
			(hide yes)
			(effects
				(font
					(size 1.27 1.27)
				)
				(justify mirror)
			)
		)
		(property "Value" ""
			(at 0 0 0)
			(layer "B.Fab")
			(effects
				(font
					(size 1.27 1.27)
				)
				(justify mirror)
			)
		)
		(duplicate_pad_numbers_are_jumpers no)
		(fp_line
			(start -0.299974 -0.150114)
			(end -0.299974 0.150114)
			(stroke
				(width 0.1)
				(type default)
			)
			(layer "B.Fab")
		)
		(fp_line
			(start -0.299974 0.150114)
			(end 0.299974 0.150114)
			(stroke
				(width 0.1)
				(type default)
			)
			(layer "B.Fab")
		)
		(fp_line
			(start 0.299974 -0.150114)
			(end -0.299974 -0.150114)
			(stroke
				(width 0.1)
				(type default)
			)
			(layer "B.Fab")
		)
		(fp_line
			(start 0.299974 0.150114)
			(end 0.299974 -0.150114)
			(stroke
				(width 0.1)
				(type default)
			)
			(layer "B.Fab")
		)
		(pad "1" smd rect
			(at 0.2667 0 180)
			(size 0.3048 0.381)
			(layers "B.Cu" "B.Mask" "B.Paste")
			(net "P0V8_PEX1")
		)
		(pad "2" smd rect
			(at -0.2667 0 180)
			(size 0.3048 0.381)
			(layers "B.Cu" "B.Mask" "B.Paste")
			(net "GND")
		)
	)
	(footprint ""
		(layer "B.Cu")
		(at 293.797228 -110.497366)
		(property "Reference" "R288"
			(at 0 0 0)
			(layer "B.SilkS")
			(hide yes)
			(effects
				(font
					(size 1.27 1.27)
				)
				(justify mirror)
			)
		)
		(property "Value" ""
			(at 0 0 0)
			(layer "B.Fab")
			(effects
				(font
					(size 1.27 1.27)
				)
				(justify mirror)
			)
		)
		(duplicate_pad_numbers_are_jumpers no)
		(fp_line
			(start -0.7874 -0.4064)
			(end -0.7874 0.4064)
			(stroke
				(width 0.1524)
				(type default)
			)
			(layer "B.SilkS")
		)
		(fp_line
			(start -0.7874 0.4064)
			(end 0.7874 0.4064)
			(stroke
				(width 0.1524)
				(type default)
			)
			(layer "B.SilkS")
		)
		(fp_line
			(start 0.7874 -0.4064)
			(end -0.7874 -0.4064)
			(stroke
				(width 0.1524)
				(type default)
			)
			(layer "B.SilkS")
		)
		(fp_line
			(start 0.7874 0.4064)
			(end 0.7874 -0.4064)
			(stroke
				(width 0.1524)
				(type default)
			)
			(layer "B.SilkS")
		)
		(fp_line
			(start -0.67945 -0.3048)
			(end -0.67945 0.3048)
			(stroke
				(width 0.1)
				(type default)
			)
			(layer "B.Fab")
		)
		(fp_line
			(start -0.67945 0.3048)
			(end -0.120396 0.3048)
			(stroke
				(width 0.1)
				(type default)
			)
			(layer "B.Fab")
		)
		(fp_line
			(start -0.12065 -0.3048)
			(end -0.67945 -0.3048)
			(stroke
				(width 0.1)
				(type default)
			)
			(layer "B.Fab")
		)
		(fp_line
			(start -0.12065 -0.2794)
			(end -0.12065 -0.3048)
			(stroke
				(width 0.1)
				(type default)
			)
			(layer "B.Fab")
		)
		(fp_line
			(start -0.120396 0.2794)
			(end 0.12065 0.2794)
			(stroke
				(width 0.1)
				(type default)
			)
			(layer "B.Fab")
		)
		(fp_line
			(start -0.120396 0.3048)
			(end -0.120396 0.2794)
			(stroke
				(width 0.1)
				(type default)
			)
			(layer "B.Fab")
		)
		(fp_line
			(start 0.12065 -0.305054)
			(end 0.12065 -0.2794)
			(stroke
				(width 0.1)
				(type default)
			)
			(layer "B.Fab")
		)
		(fp_line
			(start 0.12065 -0.2794)
			(end -0.12065 -0.2794)
			(stroke
				(width 0.1)
				(type default)
			)
			(layer "B.Fab")
		)
		(fp_line
			(start 0.12065 0.2794)
			(end 0.12065 0.3048)
			(stroke
				(width 0.1)
				(type default)
			)
			(layer "B.Fab")
		)
		(fp_line
			(start 0.12065 0.3048)
			(end 0.67945 0.3048)
			(stroke
				(width 0.1)
				(type default)
			)
			(layer "B.Fab")
		)
		(fp_line
			(start 0.67945 -0.305054)
			(end 0.12065 -0.305054)
			(stroke
				(width 0.1)
				(type default)
			)
			(layer "B.Fab")
		)
		(fp_line
			(start 0.67945 0.3048)
			(end 0.67945 -0.305054)
			(stroke
				(width 0.1)
				(type default)
			)
			(layer "B.Fab")
		)
		(pad "1" smd circle
			(at 0.40005 0 180)
			(size 0 0)
			(layers "B.Cu" "B.Mask" "B.Paste")
			(net "NIC5_BIF2_N")
		)
		(pad "2" smd circle
			(at -0.40005 0 180)
			(size 0 0)
			(layers "B.Cu" "B.Mask" "B.Paste")
			(net "P3V3_AUX")
		)
	)
	(footprint ""
		(layer "B.Cu")
		(at 24.219408 -228.346 90)
		(property "Reference" "R3447"
			(at 0 0 90)
			(layer "B.SilkS")
			(hide yes)
			(effects
				(font
					(size 1.27 1.27)
				)
				(justify mirror)
			)
		)
		(property "Value" ""
			(at 0 0 90)
			(layer "B.Fab")
			(effects
				(font
					(size 1.27 1.27)
				)
				(justify mirror)
			)
		)
		(duplicate_pad_numbers_are_jumpers no)
		(fp_line
			(start 0.7874 -0.4064)
			(end -0.7874 -0.4064)
			(stroke
				(width 0.1524)
				(type default)
			)
			(layer "B.SilkS")
		)
		(fp_line
			(start -0.7874 -0.4064)
			(end -0.7874 0.4064)
			(stroke
				(width 0.1524)
				(type default)
			)
			(layer "B.SilkS")
		)
		(fp_line
			(start 0.7874 0.4064)
			(end 0.7874 -0.4064)
			(stroke
				(width 0.1524)
				(type default)
			)
			(layer "B.SilkS")
		)
		(fp_line
			(start -0.7874 0.4064)
			(end 0.7874 0.4064)
			(stroke
				(width 0.1524)
				(type default)
			)
			(layer "B.SilkS")
		)
		(fp_line
			(start 0.67945 -0.305054)
			(end 0.12065 -0.305054)
			(stroke
				(width 0.1)
				(type default)
			)
			(layer "B.Fab")
		)
		(fp_line
			(start 0.12065 -0.305054)
			(end 0.12065 -0.2794)
			(stroke
				(width 0.1)
				(type default)
			)
			(layer "B.Fab")
		)
		(fp_line
			(start -0.12065 -0.3048)
			(end -0.67945 -0.3048)
			(stroke
				(width 0.1)
				(type default)
			)
			(layer "B.Fab")
		)
		(fp_line
			(start -0.67945 -0.3048)
			(end -0.67945 0.3048)
			(stroke
				(width 0.1)
				(type default)
			)
			(layer "B.Fab")
		)
		(fp_line
			(start 0.12065 -0.2794)
			(end -0.12065 -0.2794)
			(stroke
				(width 0.1)
				(type default)
			)
			(layer "B.Fab")
		)
		(fp_line
			(start -0.12065 -0.2794)
			(end -0.12065 -0.3048)
			(stroke
				(width 0.1)
				(type default)
			)
			(layer "B.Fab")
		)
		(fp_line
			(start 0.12065 0.2794)
			(end 0.12065 0.3048)
			(stroke
				(width 0.1)
				(type default)
			)
			(layer "B.Fab")
		)
		(fp_line
			(start -0.120396 0.2794)
			(end 0.12065 0.2794)
			(stroke
				(width 0.1)
				(type default)
			)
			(layer "B.Fab")
		)
		(fp_line
			(start 0.67945 0.3048)
			(end 0.67945 -0.305054)
			(stroke
				(width 0.1)
				(type default)
			)
			(layer "B.Fab")
		)
		(fp_line
			(start 0.12065 0.3048)
			(end 0.67945 0.3048)
			(stroke
				(width 0.1)
				(type default)
			)
			(layer "B.Fab")
		)
		(fp_line
			(start -0.120396 0.3048)
			(end -0.120396 0.2794)
			(stroke
				(width 0.1)
				(type default)
			)
			(layer "B.Fab")
		)
		(fp_line
			(start -0.67945 0.3048)
			(end -0.120396 0.3048)
			(stroke
				(width 0.1)
				(type default)
			)
			(layer "B.Fab")
		)
		(pad "1" smd circle
			(at 0.40005 0 270)
			(size 0 0)
			(layers "B.Cu" "B.Mask" "B.Paste")
			(net "SPI_PEX0_CS_MUX_N")
		)
		(pad "2" smd circle
			(at -0.40005 0 270)
			(size 0 0)
			(layers "B.Cu" "B.Mask" "B.Paste")
			(net "SPI_PEX0_CS_MUX_R_N")
		)
	)
	(footprint ""
		(layer "B.Cu")
		(at 403.199854 -288.299906 90)
		(property "Reference" "C3461"
			(at 0 0 90)
			(layer "B.SilkS")
			(hide yes)
			(effects
				(font
					(size 1.27 1.27)
				)
				(justify mirror)
			)
		)
		(property "Value" ""
			(at 0 0 90)
			(layer "B.Fab")
			(effects
				(font
					(size 1.27 1.27)
				)
				(justify mirror)
			)
		)
		(duplicate_pad_numbers_are_jumpers no)
		(fp_line
			(start 0.299974 -0.150114)
			(end -0.299974 -0.150114)
			(stroke
				(width 0.1)
				(type default)
			)
			(layer "B.Fab")
		)
		(fp_line
			(start -0.299974 -0.150114)
			(end -0.299974 0.150114)
			(stroke
				(width 0.1)
				(type default)
			)
			(layer "B.Fab")
		)
		(fp_line
			(start 0.299974 0.150114)
			(end 0.299974 -0.150114)
			(stroke
				(width 0.1)
				(type default)
			)
			(layer "B.Fab")
		)
		(fp_line
			(start -0.299974 0.150114)
			(end 0.299974 0.150114)
			(stroke
				(width 0.1)
				(type default)
			)
			(layer "B.Fab")
		)
		(pad "1" smd rect
			(at 0.2667 0 270)
			(size 0.3048 0.381)
			(layers "B.Cu" "B.Mask" "B.Paste")
			(net "P1V25_PEX3")
		)
		(pad "2" smd rect
			(at -0.2667 0 270)
			(size 0.3048 0.381)
			(layers "B.Cu" "B.Mask" "B.Paste")
			(net "GND")
		)
	)
	(footprint ""
		(layer "B.Cu")
		(at 286.569912 -305.399948 -90)
		(property "Reference" "C3319"
			(at 0 0 90)
			(layer "B.SilkS")
			(hide yes)
			(effects
				(font
					(size 1.27 1.27)
				)
				(justify mirror)
			)
		)
		(property "Value" ""
			(at 0 0 90)
			(layer "B.Fab")
			(effects
				(font
					(size 1.27 1.27)
				)
				(justify mirror)
			)
		)
		(duplicate_pad_numbers_are_jumpers no)
		(fp_line
			(start -0.299974 0.150114)
			(end 0.299974 0.150114)
			(stroke
				(width 0.1)
				(type default)
			)
			(layer "B.Fab")
		)
		(fp_line
			(start 0.299974 0.150114)
			(end 0.299974 -0.150114)
			(stroke
				(width 0.1)
				(type default)
			)
			(layer "B.Fab")
		)
		(fp_line
			(start -0.299974 -0.150114)
			(end -0.299974 0.150114)
			(stroke
				(width 0.1)
				(type default)
			)
			(layer "B.Fab")
		)
		(fp_line
			(start 0.299974 -0.150114)
			(end -0.299974 -0.150114)
			(stroke
				(width 0.1)
				(type default)
			)
			(layer "B.Fab")
		)
		(pad "1" smd rect
			(at 0.2667 0 90)
			(size 0.3048 0.381)
			(layers "B.Cu" "B.Mask" "B.Paste")
			(net "P1V25_SERDES_VDDPLL_PEX2")
		)
		(pad "2" smd rect
			(at -0.2667 0 90)
			(size 0.3048 0.381)
			(layers "B.Cu" "B.Mask" "B.Paste")
			(net "GND")
		)
	)
	(footprint ""
		(layer "B.Cu")
		(at 174.270162 -305.399948 -90)
		(property "Reference" "C3154"
			(at 0 0 90)
			(layer "B.SilkS")
			(hide yes)
			(effects
				(font
					(size 1.27 1.27)
				)
				(justify mirror)
			)
		)
		(property "Value" ""
			(at 0 0 90)
			(layer "B.Fab")
			(effects
				(font
					(size 1.27 1.27)
				)
				(justify mirror)
			)
		)
		(duplicate_pad_numbers_are_jumpers no)
		(fp_line
			(start -0.299974 0.150114)
			(end 0.299974 0.150114)
			(stroke
				(width 0.1)
				(type default)
			)
			(layer "B.Fab")
		)
		(fp_line
			(start 0.299974 0.150114)
			(end 0.299974 -0.150114)
			(stroke
				(width 0.1)
				(type default)
			)
			(layer "B.Fab")
		)
		(fp_line
			(start -0.299974 -0.150114)
			(end -0.299974 0.150114)
			(stroke
				(width 0.1)
				(type default)
			)
			(layer "B.Fab")
		)
		(fp_line
			(start 0.299974 -0.150114)
			(end -0.299974 -0.150114)
			(stroke
				(width 0.1)
				(type default)
			)
			(layer "B.Fab")
		)
		(pad "1" smd rect
			(at 0.2667 0 90)
			(size 0.3048 0.381)
			(layers "B.Cu" "B.Mask" "B.Paste")
			(net "P1V25_SERDES_VDDPLL_PEX1")
		)
		(pad "2" smd rect
			(at -0.2667 0 90)
			(size 0.3048 0.381)
			(layers "B.Cu" "B.Mask" "B.Paste")
			(net "GND")
		)
	)
)
